# T6G (Grand Teton) — schematic netlist excerpt (pin names and nets, part order shuffled) for the footprints in the layout excerpt that follows; sources: Cadence DE-HDL packaged netlist, KiCad conversion of 04192023_DAF0TMB3IC0_F0TG_MB_C_brd_V02_OCP.brd

R3109  Q_RES  0 5% CHIP  pkg 0402LF  page 248 : A = SMB_1_BMC_GPU_SCL ; B = SMB_1_BMC_GPU_R_SCL
PC6501  Q_CAP  22UF 16V 20% X6S  pkg C0805  page 360 : A = SW_P12V_AUX_P1V8_RETIMER_CPU0_FLT ; B = GND
R178  Q_RES  1K 1% CHIP  pkg 0402LF  page 144 : A = P3V3_AUX ; B = PCIE_M2_SSD0_PRSNT_N

(kicad_pcb
	(version 20260206)
	(generator "pcbnew")
	(generator_version "10.0")
	(general
		(thickness 1.6)
		(legacy_teardrops no)
	)
	(paper "A4")
	(title_block
		(title "04192023_DAF0TMB3IC0_F0TG_MB_C_brd_V02_OCP.brd")
		(comment 1 "Grand Teton / footprints 2156-2158 of 8354")
	)
	(layers
		(0 "F.Cu" signal "TOP")
		(4 "In1.Cu" signal "GND")
		(6 "In2.Cu" signal "IN1")
		(8 "In3.Cu" signal "GND1")
		(10 "In4.Cu" signal "IN2")
		(12 "In5.Cu" signal "GND2")
		(14 "In6.Cu" signal "IN3")
		(16 "In7.Cu" signal "GND3")
		(18 "In8.Cu" signal "VCC")
		(20 "In9.Cu" signal "VCC1")
		(22 "In10.Cu" signal "GND4")
		(24 "In11.Cu" signal "IN4")
		(26 "In12.Cu" signal "GND5")
		(28 "In13.Cu" signal "IN5")
		(30 "In14.Cu" signal "GND6")
		(32 "In15.Cu" signal "IN6")
		(34 "In16.Cu" signal "GND7")
		(2 "B.Cu" signal "BOTTOM")
		(9 "F.Adhes" user "F.Adhesive")
		(11 "B.Adhes" user "B.Adhesive")
		(13 "F.Paste" user "Package Geometry/Pastemask Top")
		(15 "B.Paste" user "Package Geometry/Pastemask Bottom")
		(5 "F.SilkS" user "Ref Des/Silkscreen Top")
		(7 "B.SilkS" user "Ref Des/Silkscreen Bottom")
		(1 "F.Mask" user "Board Geometry/Soldermask Top")
		(3 "B.Mask" user "Board Geometry/Soldermask Bottom")
		(17 "Dwgs.User" user "User.Drawings")
		(19 "Cmts.User" user "User.Comments")
		(21 "Eco1.User" user "User.Eco1")
		(23 "Eco2.User" user "User.Eco2")
		(25 "Edge.Cuts" user "Board Geometry/Outline")
		(27 "Margin" user)
		(31 "F.CrtYd" user "Package Geometry/Place Bound Top")
		(29 "B.CrtYd" user "Package Geometry/Place Bound Bottom")
		(35 "F.Fab" user "Ref Des/Assembly Top")
		(33 "B.Fab" user "Ref Des/Assembly Bottom")
	)
	(footprint ""
		(layer "F.Cu")
		(at 22.07768 -431.421794)
		(property "Reference" "R3109"
			(at 0 0 0)
			(layer "F.SilkS")
			(hide yes)
			(effects
				(font
					(size 1.27 1.27)
				)
			)
		)
		(property "Value" ""
			(at 0 0 0)
			(layer "F.Fab")
			(effects
				(font
					(size 1.27 1.27)
				)
			)
		)
		(duplicate_pad_numbers_are_jumpers no)
		(fp_line
			(start -0.7874 -0.4064)
			(end 0.7874 -0.4064)
			(stroke
				(width 0.1524)
				(type default)
			)
			(layer "F.SilkS")
		)
		(fp_line
			(start -0.7874 0.4064)
			(end -0.7874 -0.4064)
			(stroke
				(width 0.1524)
				(type default)
			)
			(layer "F.SilkS")
		)
		(fp_line
			(start 0.7874 -0.4064)
			(end 0.7874 0.4064)
			(stroke
				(width 0.1524)
				(type default)
			)
			(layer "F.SilkS")
		)
		(fp_line
			(start 0.7874 0.4064)
			(end -0.7874 0.4064)
			(stroke
				(width 0.1524)
				(type default)
			)
			(layer "F.SilkS")
		)
		(fp_line
			(start -0.67945 -0.305054)
			(end -0.12065 -0.305054)
			(stroke
				(width 0.1)
				(type default)
			)
			(layer "F.Fab")
		)
		(fp_line
			(start -0.67945 0.3048)
			(end -0.67945 -0.305054)
			(stroke
				(width 0.1)
				(type default)
			)
			(layer "F.Fab")
		)
		(fp_line
			(start -0.12065 -0.305054)
			(end -0.12065 -0.2794)
			(stroke
				(width 0.1)
				(type default)
			)
			(layer "F.Fab")
		)
		(fp_line
			(start -0.12065 -0.2794)
			(end 0.12065 -0.2794)
			(stroke
				(width 0.1)
				(type default)
			)
			(layer "F.Fab")
		)
		(fp_line
			(start -0.12065 0.2794)
			(end -0.12065 0.3048)
			(stroke
				(width 0.1)
				(type default)
			)
			(layer "F.Fab")
		)
		(fp_line
			(start -0.12065 0.3048)
			(end -0.67945 0.3048)
			(stroke
				(width 0.1)
				(type default)
			)
			(layer "F.Fab")
		)
		(fp_line
			(start 0.120396 0.2794)
			(end -0.12065 0.2794)
			(stroke
				(width 0.1)
				(type default)
			)
			(layer "F.Fab")
		)
		(fp_line
			(start 0.120396 0.3048)
			(end 0.120396 0.2794)
			(stroke
				(width 0.1)
				(type default)
			)
			(layer "F.Fab")
		)
		(fp_line
			(start 0.12065 -0.3048)
			(end 0.67945 -0.3048)
			(stroke
				(width 0.1)
				(type default)
			)
			(layer "F.Fab")
		)
		(fp_line
			(start 0.12065 -0.2794)
			(end 0.12065 -0.3048)
			(stroke
				(width 0.1)
				(type default)
			)
			(layer "F.Fab")
		)
		(fp_line
			(start 0.67945 -0.3048)
			(end 0.67945 0.3048)
			(stroke
				(width 0.1)
				(type default)
			)
			(layer "F.Fab")
		)
		(fp_line
			(start 0.67945 0.3048)
			(end 0.120396 0.3048)
			(stroke
				(width 0.1)
				(type default)
			)
			(layer "F.Fab")
		)
		(pad "1" smd circle
			(at -0.40005 0)
			(size 0 0)
			(layers "F.Cu" "F.Mask" "F.Paste")
			(net "SMB_1_BMC_GPU_SCL")
		)
		(pad "2" smd circle
			(at 0.40005 0)
			(size 0 0)
			(layers "F.Cu" "F.Mask" "F.Paste")
			(net "SMB_1_BMC_GPU_R_SCL")
		)
	)
	(footprint ""
		(layer "F.Cu")
		(at 244.327426 -285.631636)
		(property "Reference" "PC6501"
			(at 0 0 0)
			(layer "F.SilkS")
			(hide yes)
			(effects
				(font
					(size 1.27 1.27)
				)
			)
		)
		(property "Value" ""
			(at 0 0 0)
			(layer "F.Fab")
			(effects
				(font
					(size 1.27 1.27)
				)
			)
		)
		(duplicate_pad_numbers_are_jumpers no)
		(fp_line
			(start -1.524 -0.762)
			(end 1.524 -0.762)
			(stroke
				(width 0.1524)
				(type default)
			)
			(layer "F.SilkS")
		)
		(fp_line
			(start -1.524 0.762)
			(end -1.524 -0.762)
			(stroke
				(width 0.1524)
				(type default)
			)
			(layer "F.SilkS")
		)
		(fp_line
			(start 1.524 -0.762)
			(end 1.524 0.762)
			(stroke
				(width 0.1524)
				(type default)
			)
			(layer "F.SilkS")
		)
		(fp_line
			(start 1.524 0.762)
			(end -1.524 0.762)
			(stroke
				(width 0.1524)
				(type default)
			)
			(layer "F.SilkS")
		)
		(fp_line
			(start -1.1049 -0.724916)
			(end -1.1049 0.724916)
			(stroke
				(width 0.1)
				(type default)
			)
			(layer "F.Fab")
		)
		(fp_line
			(start -1.1049 0.724916)
			(end 1.1049 0.724916)
			(stroke
				(width 0.1)
				(type default)
			)
			(layer "F.Fab")
		)
		(fp_line
			(start 1.1049 -0.724916)
			(end -1.1049 -0.724916)
			(stroke
				(width 0.1)
				(type default)
			)
			(layer "F.Fab")
		)
		(fp_line
			(start 1.1049 0.724916)
			(end 1.1049 -0.724916)
			(stroke
				(width 0.1)
				(type default)
			)
			(layer "F.Fab")
		)
		(pad "1" smd rect
			(at -0.889 0 180)
			(size 1.016 1.27)
			(layers "F.Cu" "F.Mask" "F.Paste")
			(net "SW_P12V_AUX_P1V8_RETIMER_CPU0_FLT")
		)
		(pad "2" smd rect
			(at 0.889 0 180)
			(size 1.016 1.27)
			(layers "F.Cu" "F.Mask" "F.Paste")
			(net "GND")
		)
	)
	(footprint ""
		(layer "F.Cu")
		(at 180.777134 -56.352948 180)
		(property "Reference" "R178"
			(at 0 0 180)
			(layer "F.SilkS")
			(hide yes)
			(effects
				(font
					(size 1.27 1.27)
				)
			)
		)
		(property "Value" ""
			(at 0 0 180)
			(layer "F.Fab")
			(effects
				(font
					(size 1.27 1.27)
				)
			)
		)
		(duplicate_pad_numbers_are_jumpers no)
		(fp_line
			(start 0.7874 0.4064)
			(end -0.7874 0.4064)
			(stroke
				(width 0.1524)
				(type default)
			)
			(layer "F.SilkS")
		)
		(fp_line
			(start 0.7874 -0.4064)
			(end 0.7874 0.4064)
			(stroke
				(width 0.1524)
				(type default)
			)
			(layer "F.SilkS")
		)
		(fp_line
			(start -0.7874 0.4064)
			(end -0.7874 -0.4064)
			(stroke
				(width 0.1524)
				(type default)
			)
			(layer "F.SilkS")
		)
		(fp_line
			(start -0.7874 -0.4064)
			(end 0.7874 -0.4064)
			(stroke
				(width 0.1524)
				(type default)
			)
			(layer "F.SilkS")
		)
		(fp_line
			(start 0.67945 0.3048)
			(end 0.120396 0.3048)
			(stroke
				(width 0.1)
				(type default)
			)
			(layer "F.Fab")
		)
		(fp_line
			(start 0.67945 -0.3048)
			(end 0.67945 0.3048)
			(stroke
				(width 0.1)
				(type default)
			)
			(layer "F.Fab")
		)
		(fp_line
			(start 0.12065 -0.2794)
			(end 0.12065 -0.3048)
			(stroke
				(width 0.1)
				(type default)
			)
			(layer "F.Fab")
		)
		(fp_line
			(start 0.12065 -0.3048)
			(end 0.67945 -0.3048)
			(stroke
				(width 0.1)
				(type default)
			)
			(layer "F.Fab")
		)
		(fp_line
			(start 0.120396 0.3048)
			(end 0.120396 0.2794)
			(stroke
				(width 0.1)
				(type default)
			)
			(layer "F.Fab")
		)
		(fp_line
			(start 0.120396 0.2794)
			(end -0.12065 0.2794)
			(stroke
				(width 0.1)
				(type default)
			)
			(layer "F.Fab")
		)
		(fp_line
			(start -0.12065 0.3048)
			(end -0.67945 0.3048)
			(stroke
				(width 0.1)
				(type default)
			)
			(layer "F.Fab")
		)
		(fp_line
			(start -0.12065 0.2794)
			(end -0.12065 0.3048)
			(stroke
				(width 0.1)
				(type default)
			)
			(layer "F.Fab")
		)
		(fp_line
			(start -0.12065 -0.2794)
			(end 0.12065 -0.2794)
			(stroke
				(width 0.1)
				(type default)
			)
			(layer "F.Fab")
		)
		(fp_line
			(start -0.12065 -0.305054)
			(end -0.12065 -0.2794)
			(stroke
				(width 0.1)
				(type default)
			)
			(layer "F.Fab")
		)
		(fp_line
			(start -0.67945 0.3048)
			(end -0.67945 -0.305054)
			(stroke
				(width 0.1)
				(type default)
			)
			(layer "F.Fab")
		)
		(fp_line
			(start -0.67945 -0.305054)
			(end -0.12065 -0.305054)
			(stroke
				(width 0.1)
				(type default)
			)
			(layer "F.Fab")
		)
		(pad "1" smd circle
			(at -0.40005 0 180)
			(size 0 0)
			(layers "F.Cu" "F.Mask" "F.Paste")
			(net "P3V3_AUX")
		)
		(pad "2" smd circle
			(at 0.40005 0 180)
			(size 0 0)
			(layers "F.Cu" "F.Mask" "F.Paste")
			(net "PCIE_M2_SSD0_PRSNT_N")
		)
	)
)
